(kicad_pcb
	(version 20241229)
	(generator "pcbnew")
	(generator_version "9.0")
	(general
		(thickness 1.711)
		(legacy_teardrops no)
	)
	(paper "A4")
	(title_block
		(title "Antmicro Baseboard for Jetson AGX Thor")
		(date "2026-02-18")
		(rev "1.1.0")
		(company "Antmicro Ltd")
		(comment 1 "www.antmicro.com")
		(comment 9 "footprints 222-225 of 1170")
	)
	(layers
		(0 "F.Cu" signal)
		(4 "In1.Cu" signal)
		(6 "In2.Cu" signal)
		(8 "In3.Cu" signal)
		(10 "In4.Cu" jumper)
		(12 "In5.Cu" signal)
		(14 "In6.Cu" signal)
		(16 "In7.Cu" signal)
		(18 "In8.Cu" signal)
		(2 "B.Cu" signal)
		(9 "F.Adhes" user "F.Adhesive")
		(11 "B.Adhes" user "B.Adhesive")
		(13 "F.Paste" user)
		(15 "B.Paste" user)
		(5 "F.SilkS" user "F.Silkscreen")
		(7 "B.SilkS" user "B.Silkscreen")
		(1 "F.Mask" user)
		(3 "B.Mask" user)
		(17 "Dwgs.User" user "User.Drawings")
		(19 "Cmts.User" user "User.Comments")
		(21 "Eco1.User" user "User.Eco1")
		(23 "Eco2.User" user "User.Eco2")
		(25 "Edge.Cuts" user)
		(27 "Margin" user)
		(31 "F.CrtYd" user "F.Courtyard")
		(29 "B.CrtYd" user "B.Courtyard")
		(35 "F.Fab" user)
		(33 "B.Fab" user)
	)
	(footprint "antmicro-footprints:R_0402_1005Metric"
		(layer "F.Cu")
		(at 94 64.5 180)
		(descr "Resistor SMD 0402")
		(tags "resistor SMD 0402")
		(property "Reference" "R296"
			(at -9.75 -0.5 0)
			(layer "F.SilkS")
			(effects
				(font
					(size 0.7 0.7)
					(thickness 0.15)
				)
				(justify right top)
			)
		)
		(property "Value" "R_49k9_0402"
			(at -1.011843 1.772046 0)
			(layer "F.Fab")
			(effects
				(font
					(size 0.7 0.7)
					(thickness 0.15)
				)
				(justify right top)
			)
		)
		(property "Datasheet" "https://www.bourns.com/docs/product-datasheets/cr.pdf"
			(at 0 0 0)
			(layer "F.Fab")
			(hide yes)
			(effects
				(font
					(size 1.27 1.27)
					(thickness 0.15)
				)
			)
		)
		(property "Description" "SMD Chip Resistor, 49.9 kohm, ± 1%, 63 mW, 0402 [1005 Metric], Thick Film, General Purpose"
			(at 0 0 0)
			(layer "F.Fab")
			(hide yes)
			(effects
				(font
					(size 1.27 1.27)
					(thickness 0.15)
				)
			)
		)
		(property "MPN" "CR0402-FX-4992GLF"
			(at 0 0 180)
			(unlocked yes)
			(layer "F.Fab")
			(hide yes)
			(effects
				(font
					(size 1 1)
					(thickness 0.15)
				)
			)
		)
		(property "Manufacturer" "Bourns"
			(at 0 0 180)
			(unlocked yes)
			(layer "F.Fab")
			(hide yes)
			(effects
				(font
					(size 1 1)
					(thickness 0.15)
				)
			)
		)
		(property "License" "Apache-2.0"
			(at 0 0 180)
			(unlocked yes)
			(layer "F.Fab")
			(hide yes)
			(effects
				(font
					(size 1 1)
					(thickness 0.15)
				)
			)
		)
		(property "Author" "Antmicro"
			(at 0 0 180)
			(unlocked yes)
			(layer "F.Fab")
			(hide yes)
			(effects
				(font
					(size 1 1)
					(thickness 0.15)
				)
			)
		)
		(property "Val" "49k9"
			(at 0 0 180)
			(unlocked yes)
			(layer "F.Fab")
			(hide yes)
			(effects
				(font
					(size 1 1)
					(thickness 0.15)
				)
			)
		)
		(property "Tolerance" "1%"
			(at 0 0 180)
			(unlocked yes)
			(layer "F.Fab")
			(hide yes)
			(effects
				(font
					(size 1 1)
					(thickness 0.15)
				)
			)
		)
		(property "Current" "1A"
			(at 0 0 180)
			(unlocked yes)
			(layer "F.Fab")
			(hide yes)
			(effects
				(font
					(size 1 1)
					(thickness 0.15)
				)
			)
		)
		(sheetname "/SoM_Power/")
		(sheetfile "som_power.kicad_sch")
		(attr smd)
		(fp_poly
			(pts
				(xy -0.925 -0.47) (xy -0.925 0.47) (xy 0.925 0.47) (xy 0.925 -0.47)
			)
			(stroke
				(width 0.05)
				(type default)
			)
			(fill no)
			(layer "F.CrtYd")
		)
		(fp_poly
			(pts
				(xy -0.5 -0.25) (xy -0.5 0.25) (xy 0.5 0.25) (xy 0.5 -0.25)
			)
			(stroke
				(width 0.15)
				(type solid)
			)
			(fill no)
			(layer "F.Fab")
		)
		(fp_text user "Author: Antmicro"
			(at -0.95 4.169 0)
			(layer "F.Fab")
			(effects
				(font
					(size 0.7 0.7)
					(thickness 0.15)
				)
				(justify right top)
			)
		)
		(fp_text user "License: Apache-2.0"
			(at -0.949999 5.169 0)
			(layer "F.Fab")
			(effects
				(font
					(size 0.7 0.7)
					(thickness 0.15)
				)
				(justify right top)
			)
		)
		(fp_text user "${REFERENCE}"
			(at -0.95 3.168 0)
			(layer "F.Fab")
			(effects
				(font
					(size 0.7 0.7)
					(thickness 0.15)
				)
				(justify right top)
			)
		)
		(pad "1" smd roundrect
			(at -0.48 0 180)
			(size 0.59 0.64)
			(layers "F.Cu" "F.Mask" "F.Paste")
			(roundrect_rratio 0.25)
			(net 1285 "/SoM_Power/VIN_PWR_ON")
			(pintype "passive")
		)
		(pad "2" smd roundrect
			(at 0.48 0 180)
			(size 0.59 0.64)
			(layers "F.Cu" "F.Mask" "F.Paste")
			(roundrect_rratio 0.25)
			(net 4 "+3V3_AON")
			(pintype "passive")
		)
	)
	(footprint "antmicro-footprints:SOD-523"
		(layer "F.Cu")
		(at 186.22 123.499)
		(property "Reference" "D15"
			(at -1.42 1.54 0)
			(layer "F.SilkS")
			(effects
				(font
					(size 0.7 0.7)
					(thickness 0.15)
				)
				(justify left bottom)
			)
		)
		(property "Value" "RB521S30T1G"
			(at 0 1.499 0)
			(layer "F.Fab")
			(effects
				(font
					(size 0.7 0.7)
					(thickness 0.15)
				)
				(justify left bottom)
			)
		)
		(property "Datasheet" "https://www.onsemi.com/pdf/datasheet/rb521s30t1-d.pdf"
			(at 0 0 0)
			(layer "F.Fab")
			(hide yes)
			(effects
				(font
					(size 1.27 1.27)
					(thickness 0.15)
				)
			)
		)
		(property "Description" "Small Signal Schottky Diode, Single, 30 V, 200 mA, 500 mV, 1 A, 125 °C"
			(at 0 0 0)
			(layer "F.Fab")
			(hide yes)
			(effects
				(font
					(size 1.27 1.27)
					(thickness 0.15)
				)
			)
		)
		(property "MPN" "RB521S30T1G"
			(at 0 0 0)
			(unlocked yes)
			(layer "F.Fab")
			(hide yes)
			(effects
				(font
					(size 1 1)
					(thickness 0.15)
				)
			)
		)
		(property "Manufacturer" "ON Semiconductor"
			(at 0 0 0)
			(unlocked yes)
			(layer "F.Fab")
			(hide yes)
			(effects
				(font
					(size 1 1)
					(thickness 0.15)
				)
			)
		)
		(property "Author" "Antmicro"
			(at 0 0 0)
			(unlocked yes)
			(layer "F.Fab")
			(hide yes)
			(effects
				(font
					(size 1 1)
					(thickness 0.15)
				)
			)
		)
		(property "License" "Apache-2.0"
			(at 0 0 0)
			(unlocked yes)
			(layer "F.Fab")
			(hide yes)
			(effects
				(font
					(size 1 1)
					(thickness 0.15)
				)
			)
		)
		(sheetname "/USB Hub/")
		(sheetfile "usb_hub.kicad_sch")
		(attr smd)
		(fp_line
			(start -0.35 -0.5)
			(end -0.35 0.5)
			(stroke
				(width 0.15)
				(type solid)
			)
			(layer "F.SilkS")
		)
		(fp_poly
			(pts
				(xy -1 -0.6) (xy 1 -0.6) (xy 1 0.6) (xy -1 0.6)
			)
			(stroke
				(width 0.05)
				(type solid)
			)
			(fill no)
			(layer "F.CrtYd")
		)
		(fp_line
			(start -0.652 -0.425)
			(end 0.65 -0.425)
			(stroke
				(width 0.15)
				(type solid)
			)
			(layer "F.Fab")
		)
		(fp_line
			(start -0.652 0.423)
			(end -0.652 -0.425)
			(stroke
				(width 0.15)
				(type solid)
			)
			(layer "F.Fab")
		)
		(fp_line
			(start -0.652 0.423)
			(end 0.65 0.423)
			(stroke
				(width 0.15)
				(type solid)
			)
			(layer "F.Fab")
		)
		(fp_line
			(start -0.35 -0.4)
			(end -0.35 0.4)
			(stroke
				(width 0.15)
				(type solid)
			)
			(layer "F.Fab")
		)
		(fp_line
			(start 0.65 -0.425)
			(end 0.65 0.423)
			(stroke
				(width 0.15)
				(type solid)
			)
			(layer "F.Fab")
		)
		(fp_text user "${REFERENCE}"
			(at -1.276 3.499 0)
			(layer "F.Fab")
			(effects
				(font
					(size 0.7 0.7)
					(thickness 0.15)
				)
				(justify left bottom)
			)
		)
		(fp_text user "Author: Antmicro"
			(at -1.276 4.7 0)
			(layer "F.Fab")
			(effects
				(font
					(size 0.7 0.7)
					(thickness 0.15)
				)
				(justify left bottom)
			)
		)
		(fp_text user "License: Apache-2.0"
			(at -1.276 5.9 0)
			(layer "F.Fab")
			(effects
				(font
					(size 0.7 0.7)
					(thickness 0.15)
				)
				(justify left bottom)
			)
		)
		(pad "1" smd roundrect
			(at -0.701 0)
			(size 0.5 0.6)
			(layers "F.Cu" "F.Mask" "F.Paste")
			(roundrect_rratio 0.25)
			(net 271 "FLASH_PWR")
			(pinfunction "C")
			(pintype "passive")
		)
		(pad "2" smd roundrect
			(at 0.699001 0)
			(size 0.5 0.6)
			(layers "F.Cu" "F.Mask" "F.Paste")
			(roundrect_rratio 0.25)
			(net 2 "+3V3")
			(pinfunction "A")
			(pintype "passive")
		)
	)
	(footprint "antmicro-footprints:Molex_Mini-Fit_2x3_50362462"
		(locked yes)
		(layer "F.Cu")
		(at 228.031 59.49 -90)
		(property "Reference" "J2"
			(at -3.89 -10.74 0)
			(layer "F.SilkS")
			(effects
				(font
					(size 0.7 0.7)
					(thickness 0.15)
				)
				(justify right top)
			)
		)
		(property "Value" "Molex_Mini-Fit_2x3_50362462"
			(at -3.85 8.2 90)
			(layer "F.Fab")
			(effects
				(font
					(size 0.7 0.7)
					(thickness 0.15)
				)
				(justify right top)
			)
		)
		(property "Datasheet" "https://www.molex.com/content/dam/molex/molex-dot-com/products/automated/en-us/salesdrawingpdf/556/5569/050362462_sd.pdf?inline"
			(at 0 0 90)
			(layer "F.Fab")
			(effects
				(font
					(size 0.7 0.7)
					(thickness 0.15)
				)
				(justify right top)
			)
		)
		(property "Description" "Pin Header, Wire-to-Board, 2 Rows, 6 Contacts, Through Hole Right-Angle, Mini-Fit, 13A/pin, 600V, 4.2mm"
			(at 0 0 90)
			(layer "F.Fab")
			(effects
				(font
					(size 0.7 0.7)
					(thickness 0.15)
				)
				(justify right top)
			)
		)
		(property "MPN" "50362462"
			(at 0 0 270)
			(unlocked yes)
			(layer "F.Fab")
			(hide yes)
			(effects
				(font
					(size 1 1)
					(thickness 0.15)
				)
			)
		)
		(property "Manufacturer" "Molex"
			(at 0 0 270)
			(unlocked yes)
			(layer "F.Fab")
			(hide yes)
			(effects
				(font
					(size 1 1)
					(thickness 0.15)
				)
			)
		)
		(property "Author" "Antmicro"
			(at 0 0 270)
			(unlocked yes)
			(layer "F.Fab")
			(hide yes)
			(effects
				(font
					(size 1 1)
					(thickness 0.15)
				)
			)
		)
		(property "License" "Apache-2.0"
			(at 0 0 270)
			(unlocked yes)
			(layer "F.Fab")
			(hide yes)
			(effects
				(font
					(size 1 1)
					(thickness 0.15)
				)
			)
		)
		(sheetname "/Power/")
		(sheetfile "power.kicad_sch")
		(attr through_hole)
		(fp_line
			(start -2.7 -1)
			(end -1.4 -1)
			(stroke
				(width 0.15)
				(type solid)
			)
			(layer "F.SilkS")
		)
		(fp_line
			(start -2.7 -1)
			(end -2.7 -13.9)
			(stroke
				(width 0.15)
				(type solid)
			)
			(layer "F.SilkS")
		)
		(fp_line
			(start 9.8 -1)
			(end 11.1 -1)
			(stroke
				(width 0.15)
				(type solid)
			)
			(layer "F.SilkS")
		)
		(fp_line
			(start -2.7 -13.9)
			(end 11.1 -13.9)
			(stroke
				(width 0.15)
				(type solid)
			)
			(layer "F.SilkS")
		)
		(fp_line
			(start 11.1 -13.9)
			(end 11.1 -1)
			(stroke
				(width 0.15)
				(type solid)
			)
			(layer "F.SilkS")
		)
		(fp_circle
			(center -1.5 0)
			(end -1.45 0)
			(stroke
				(width 0.15)
				(type solid)
			)
			(fill yes)
			(layer "F.SilkS")
		)
		(fp_rect
			(start -3.5 -14.3)
			(end 11.5 7.1)
			(stroke
				(width 0.05)
				(type solid)
			)
			(fill no)
			(layer "F.CrtYd")
		)
		(fp_line
			(start -2.7 6.4)
			(end -2.7 -13.9)
			(stroke
				(width 0.15)
				(type solid)
			)
			(layer "F.Fab")
		)
		(fp_line
			(start 11.1 6.4)
			(end -2.7 6.4)
			(stroke
				(width 0.15)
				(type solid)
			)
			(layer "F.Fab")
		)
		(fp_line
			(start -2.7 -13.9)
			(end 11.1 -13.9)
			(stroke
				(width 0.15)
				(type solid)
			)
			(layer "F.Fab")
		)
		(fp_line
			(start 11.1 -13.9)
			(end 11.1 6.4)
			(stroke
				(width 0.15)
				(type solid)
			)
			(layer "F.Fab")
		)
		(fp_text user "Author: Antmicro"
			(at -3.85 10.6 90)
			(layer "F.Fab")
			(effects
				(font
					(size 0.7 0.7)
					(thickness 0.15)
				)
				(justify right top)
			)
		)
		(fp_text user "License: Apache-2.0"
			(at -3.85 9.4 90)
			(layer "F.Fab")
			(effects
				(font
					(size 0.7 0.7)
					(thickness 0.15)
				)
				(justify right top)
			)
		)
		(fp_text user "${REFERENCE}"
			(at -3.85 11.8 90)
			(layer "F.Fab")
			(effects
				(font
					(size 0.7 0.7)
					(thickness 0.15)
				)
				(justify right top)
			)
		)
		(pad "" np_thru_hole circle
			(at 0 -7.3 90)
			(size 3.05 3.05)
			(drill 3)
			(layers "*.Cu" "*.Mask")
		)
		(pad "" np_thru_hole circle
			(at 8.4 -7.3 90)
			(size 3.05 3.05)
			(drill 3)
			(layers "*.Cu" "*.Mask")
		)
		(pad "1" thru_hole rect
			(at 0 0 90)
			(size 2.4 2.4)
			(drill 1.8)
			(layers "*.Cu" "*.Mask")
			(remove_unused_layers no)
			(net 3 "VCC_IN")
			(pinfunction "1")
			(pintype "input")
		)
		(pad "2" thru_hole circle
			(at 4.2 0 90)
			(size 2.4 2.4)
			(drill 1.8)
			(layers "*.Cu" "*.Mask")
			(remove_unused_layers no)
			(net 3 "VCC_IN")
			(pinfunction "2")
			(pintype "input")
		)
		(pad "3" thru_hole circle
			(at 8.4 0 90)
			(size 2.4 2.4)
			(drill 1.8)
			(layers "*.Cu" "*.Mask")
			(remove_unused_layers no)
			(net 3 "VCC_IN")
			(pinfunction "3")
			(pintype "input")
		)
		(pad "4" thru_hole circle
			(at 0 5.5 90)
			(size 2.4 2.4)
			(drill 1.8)
			(layers "*.Cu" "*.Mask")
			(remove_unused_layers no)
			(net 1 "GND")
			(pinfunction "4")
			(pintype "input")
		)
		(pad "5" thru_hole circle
			(at 4.2 5.5 90)
			(size 2.4 2.4)
			(drill 1.8)
			(layers "*.Cu" "*.Mask")
			(remove_unused_layers no)
			(net 1 "GND")
			(pinfunction "5")
			(pintype "input")
		)
		(pad "6" thru_hole circle
			(at 8.4 5.5 90)
			(size 2.4 2.4)
			(drill 1.8)
			(layers "*.Cu" "*.Mask")
			(remove_unused_layers no)
			(net 1 "GND")
			(pinfunction "6")
			(pintype "input")
		)
	)
	(footprint "antmicro-footprints:R_0402_1005Metric"
		(layer "F.Cu")
		(at 67.8 85.88 90)
		(descr "Resistor SMD 0402")
		(tags "resistor SMD 0402")
		(property "Reference" "R165"
			(at 0.86 0.4 90)
			(layer "F.SilkS")
			(effects
				(font
					(size 0.7 0.7)
					(thickness 0.15)
				)
				(justify left bottom)
			)
		)
		(property "Value" "R_10k_0402"
			(at -1.011843 1.772047 90)
			(layer "F.Fab")
			(effects
				(font
					(size 0.7 0.7)
					(thickness 0.15)
				)
				(justify left bottom)
			)
		)
		(property "Datasheet" "https://www.bourns.com/docs/product-datasheets/cr.pdf"
			(at 0 0 90)
			(layer "F.Fab")
			(hide yes)
			(effects
				(font
					(size 1.27 1.27)
					(thickness 0.15)
				)
			)
		)
		(property "Description" "SMD Chip Resistor, 10 kohm, ± 1%, 62.5 mW, 0402 [1005 Metric], Thick Film, General Purpose"
			(at 0 0 90)
			(layer "F.Fab")
			(hide yes)
			(effects
				(font
					(size 1.27 1.27)
					(thickness 0.15)
				)
			)
		)
		(property "Manufacturer" "Bourns"
			(at 0 0 90)
			(unlocked yes)
			(layer "F.Fab")
			(hide yes)
			(effects
				(font
					(size 1 1)
					(thickness 0.15)
				)
			)
		)
		(property "MPN" "CR0402-FX-1002GLF"
			(at 0 0 90)
			(unlocked yes)
			(layer "F.Fab")
			(hide yes)
			(effects
				(font
					(size 1 1)
					(thickness 0.15)
				)
			)
		)
		(property "Val" "10k"
			(at 0 0 90)
			(unlocked yes)
			(layer "F.Fab")
			(hide yes)
			(effects
				(font
					(size 1 1)
					(thickness 0.15)
				)
			)
		)
		(property "License" "Apache-2.0"
			(at 0 0 90)
			(unlocked yes)
			(layer "F.Fab")
			(hide yes)
			(effects
				(font
					(size 1 1)
					(thickness 0.15)
				)
			)
		)
		(property "Author" "Antmicro"
			(at 0 0 90)
			(unlocked yes)
			(layer "F.Fab")
			(hide yes)
			(effects
				(font
					(size 1 1)
					(thickness 0.15)
				)
			)
		)
		(property "Tolerance" "1%"
			(at 0 0 90)
			(unlocked yes)
			(layer "F.Fab")
			(hide yes)
			(effects
				(font
					(size 1 1)
					(thickness 0.15)
				)
			)
		)
		(sheetname "/CSI/")
		(sheetfile "csi.kicad_sch")
		(attr smd exclude_from_pos_files exclude_from_bom dnp)
		(fp_rect
			(start -0.925 -0.47)
			(end 0.925 0.47)
			(stroke
				(width 0.05)
				(type default)
			)
			(fill no)
			(layer "F.CrtYd")
		)
		(fp_rect
			(start -0.5 -0.25)
			(end 0.5 0.25)
			(stroke
				(width 0.15)
				(type solid)
			)
			(fill no)
			(layer "F.Fab")
		)
		(fp_text user "${REFERENCE}"
			(at -0.95 3.168 90)
			(layer "F.Fab")
			(effects
				(font
					(size 0.7 0.7)
					(thickness 0.15)
				)
				(justify left bottom)
			)
		)
		(fp_text user "Author: Antmicro"
			(at -0.95 4.169 90)
			(layer "F.Fab")
			(effects
				(font
					(size 0.7 0.7)
					(thickness 0.15)
				)
				(justify left bottom)
			)
		)
		(fp_text user "License: Apache-2.0"
			(at -0.95 5.169 90)
			(layer "F.Fab")
			(effects
				(font
					(size 0.7 0.7)
					(thickness 0.15)
				)
				(justify left bottom)
			)
		)
		(pad "1" smd roundrect
			(at -0.48 0 90)
			(size 0.59 0.64)
			(layers "F.Cu" "F.Mask" "F.Paste")
			(roundrect_rratio 0.25)
			(net 74 "/CSI/CAM_CTRL.CSIA_PEN")
			(pintype "passive")
		)
		(pad "2" smd roundrect
			(at 0.48 0 90)
			(size 0.59 0.64)
			(layers "F.Cu" "F.Mask" "F.Paste")
			(roundrect_rratio 0.25)
			(net 2 "+3V3")
			(pintype "passive")
		)
	)
)
